# T6G (Grand Teton) — schematic netlist excerpt (pin names and nets, part order shuffled) for the footprints in the layout excerpt that follows; sources: Cadence DE-HDL packaged netlist, KiCad conversion of 04192023_DAF0TMB3IC0_F0TG_MB_C_brd_V02_OCP.brd

R2425  Q_RES  33.2 1% CHIP  pkg 0402LF  page 150 : A = SMB_OCP_V3_2_3V3AUX_SCL ; B = SMB_OCP_V3_2_3V3AUX_SCL_R0
PC332_2  Q_CAP  22UF 16V 20% X6S  pkg C0805  page 215 : A = SW_P12V_AUX_PVDDCR_SOC_P1_FLT ; B = GND
C2405  Q_CAP  22UF 4V 20% X6S  pkg C0402  page 73 : A = PVDDCR_CPU1_P1 ; B = GND

(kicad_pcb
	(version 20260206)
	(generator "pcbnew")
	(generator_version "10.0")
	(general
		(thickness 1.6)
		(legacy_teardrops no)
	)
	(paper "A4")
	(title_block
		(title "04192023_DAF0TMB3IC0_F0TG_MB_C_brd_V02_OCP.brd")
		(comment 1 "Grand Teton / footprints 7532-7534 of 8354")
	)
	(layers
		(0 "F.Cu" signal "TOP")
		(4 "In1.Cu" signal "GND")
		(6 "In2.Cu" signal "IN1")
		(8 "In3.Cu" signal "GND1")
		(10 "In4.Cu" signal "IN2")
		(12 "In5.Cu" signal "GND2")
		(14 "In6.Cu" signal "IN3")
		(16 "In7.Cu" signal "GND3")
		(18 "In8.Cu" signal "VCC")
		(20 "In9.Cu" signal "VCC1")
		(22 "In10.Cu" signal "GND4")
		(24 "In11.Cu" signal "IN4")
		(26 "In12.Cu" signal "GND5")
		(28 "In13.Cu" signal "IN5")
		(30 "In14.Cu" signal "GND6")
		(32 "In15.Cu" signal "IN6")
		(34 "In16.Cu" signal "GND7")
		(2 "B.Cu" signal "BOTTOM")
		(9 "F.Adhes" user "F.Adhesive")
		(11 "B.Adhes" user "B.Adhesive")
		(13 "F.Paste" user "Package Geometry/Pastemask Top")
		(15 "B.Paste" user "Package Geometry/Pastemask Bottom")
		(5 "F.SilkS" user "Ref Des/Silkscreen Top")
		(7 "B.SilkS" user "Ref Des/Silkscreen Bottom")
		(1 "F.Mask" user "Board Geometry/Soldermask Top")
		(3 "B.Mask" user "Board Geometry/Soldermask Bottom")
		(17 "Dwgs.User" user "User.Drawings")
		(19 "Cmts.User" user "User.Comments")
		(21 "Eco1.User" user "User.Eco1")
		(23 "Eco2.User" user "User.Eco2")
		(25 "Edge.Cuts" user "Board Geometry/Outline")
		(27 "Margin" user)
		(31 "F.CrtYd" user "Package Geometry/Place Bound Top")
		(29 "B.CrtYd" user "Package Geometry/Place Bound Bottom")
		(35 "F.Fab" user "Ref Des/Assembly Top")
		(33 "B.Fab" user "Ref Des/Assembly Bottom")
	)
	(footprint ""
		(layer "B.Cu")
		(at 123.357386 -267.49883)
		(property "Reference" "C2405"
			(at 0 0 0)
			(layer "B.SilkS")
			(hide yes)
			(effects
				(font
					(size 1.27 1.27)
				)
				(justify mirror)
			)
		)
		(property "Value" ""
			(at 0 0 0)
			(layer "B.Fab")
			(effects
				(font
					(size 1.27 1.27)
				)
				(justify mirror)
			)
		)
		(duplicate_pad_numbers_are_jumpers no)
		(fp_line
			(start -0.7874 -0.4064)
			(end -0.7874 0.4064)
			(stroke
				(width 0.1524)
				(type default)
			)
			(layer "B.SilkS")
		)
		(fp_line
			(start -0.7874 0.4064)
			(end 0.7874 0.4064)
			(stroke
				(width 0.1524)
				(type default)
			)
			(layer "B.SilkS")
		)
		(fp_line
			(start 0.7874 -0.4064)
			(end -0.7874 -0.4064)
			(stroke
				(width 0.1524)
				(type default)
			)
			(layer "B.SilkS")
		)
		(fp_line
			(start 0.7874 0.4064)
			(end 0.7874 -0.4064)
			(stroke
				(width 0.1524)
				(type default)
			)
			(layer "B.SilkS")
		)
		(fp_line
			(start -0.67945 -0.3048)
			(end -0.67945 0.3048)
			(stroke
				(width 0.1)
				(type default)
			)
			(layer "B.Fab")
		)
		(fp_line
			(start -0.67945 0.3048)
			(end -0.120396 0.3048)
			(stroke
				(width 0.1)
				(type default)
			)
			(layer "B.Fab")
		)
		(fp_line
			(start -0.12065 -0.3048)
			(end -0.67945 -0.3048)
			(stroke
				(width 0.1)
				(type default)
			)
			(layer "B.Fab")
		)
		(fp_line
			(start -0.12065 -0.2794)
			(end -0.12065 -0.3048)
			(stroke
				(width 0.1)
				(type default)
			)
			(layer "B.Fab")
		)
		(fp_line
			(start -0.120396 0.2794)
			(end 0.12065 0.2794)
			(stroke
				(width 0.1)
				(type default)
			)
			(layer "B.Fab")
		)
		(fp_line
			(start -0.120396 0.3048)
			(end -0.120396 0.2794)
			(stroke
				(width 0.1)
				(type default)
			)
			(layer "B.Fab")
		)
		(fp_line
			(start 0.12065 -0.305054)
			(end 0.12065 -0.2794)
			(stroke
				(width 0.1)
				(type default)
			)
			(layer "B.Fab")
		)
		(fp_line
			(start 0.12065 -0.2794)
			(end -0.12065 -0.2794)
			(stroke
				(width 0.1)
				(type default)
			)
			(layer "B.Fab")
		)
		(fp_line
			(start 0.12065 0.2794)
			(end 0.12065 0.3048)
			(stroke
				(width 0.1)
				(type default)
			)
			(layer "B.Fab")
		)
		(fp_line
			(start 0.12065 0.3048)
			(end 0.67945 0.3048)
			(stroke
				(width 0.1)
				(type default)
			)
			(layer "B.Fab")
		)
		(fp_line
			(start 0.67945 -0.305054)
			(end 0.12065 -0.305054)
			(stroke
				(width 0.1)
				(type default)
			)
			(layer "B.Fab")
		)
		(fp_line
			(start 0.67945 0.3048)
			(end 0.67945 -0.305054)
			(stroke
				(width 0.1)
				(type default)
			)
			(layer "B.Fab")
		)
		(pad "1" smd circle
			(at 0.40005 0 180)
			(size 0 0)
			(layers "B.Cu" "B.Mask" "B.Paste")
			(net "PVDDCR_CPU1_P1")
		)
		(pad "2" smd circle
			(at -0.40005 0 180)
			(size 0 0)
			(layers "B.Cu" "B.Mask" "B.Paste")
			(net "GND")
		)
	)
	(footprint ""
		(layer "B.Cu")
		(at 174.202852 -8.05688 -90)
		(property "Reference" "R2425"
			(at 0 0 90)
			(layer "B.SilkS")
			(hide yes)
			(effects
				(font
					(size 1.27 1.27)
				)
				(justify mirror)
			)
		)
		(property "Value" ""
			(at 0 0 90)
			(layer "B.Fab")
			(effects
				(font
					(size 1.27 1.27)
				)
				(justify mirror)
			)
		)
		(duplicate_pad_numbers_are_jumpers no)
		(fp_line
			(start -0.7874 0.4064)
			(end 0.7874 0.4064)
			(stroke
				(width 0.1524)
				(type default)
			)
			(layer "B.SilkS")
		)
		(fp_line
			(start 0.7874 0.4064)
			(end 0.7874 -0.4064)
			(stroke
				(width 0.1524)
				(type default)
			)
			(layer "B.SilkS")
		)
		(fp_line
			(start -0.7874 -0.4064)
			(end -0.7874 0.4064)
			(stroke
				(width 0.1524)
				(type default)
			)
			(layer "B.SilkS")
		)
		(fp_line
			(start 0.7874 -0.4064)
			(end -0.7874 -0.4064)
			(stroke
				(width 0.1524)
				(type default)
			)
			(layer "B.SilkS")
		)
		(fp_line
			(start -0.67945 0.3048)
			(end -0.120396 0.3048)
			(stroke
				(width 0.1)
				(type default)
			)
			(layer "B.Fab")
		)
		(fp_line
			(start -0.120396 0.3048)
			(end -0.120396 0.2794)
			(stroke
				(width 0.1)
				(type default)
			)
			(layer "B.Fab")
		)
		(fp_line
			(start 0.12065 0.3048)
			(end 0.67945 0.3048)
			(stroke
				(width 0.1)
				(type default)
			)
			(layer "B.Fab")
		)
		(fp_line
			(start 0.67945 0.3048)
			(end 0.67945 -0.305054)
			(stroke
				(width 0.1)
				(type default)
			)
			(layer "B.Fab")
		)
		(fp_line
			(start -0.120396 0.2794)
			(end 0.12065 0.2794)
			(stroke
				(width 0.1)
				(type default)
			)
			(layer "B.Fab")
		)
		(fp_line
			(start 0.12065 0.2794)
			(end 0.12065 0.3048)
			(stroke
				(width 0.1)
				(type default)
			)
			(layer "B.Fab")
		)
		(fp_line
			(start -0.12065 -0.2794)
			(end -0.12065 -0.3048)
			(stroke
				(width 0.1)
				(type default)
			)
			(layer "B.Fab")
		)
		(fp_line
			(start 0.12065 -0.2794)
			(end -0.12065 -0.2794)
			(stroke
				(width 0.1)
				(type default)
			)
			(layer "B.Fab")
		)
		(fp_line
			(start -0.67945 -0.3048)
			(end -0.67945 0.3048)
			(stroke
				(width 0.1)
				(type default)
			)
			(layer "B.Fab")
		)
		(fp_line
			(start -0.12065 -0.3048)
			(end -0.67945 -0.3048)
			(stroke
				(width 0.1)
				(type default)
			)
			(layer "B.Fab")
		)
		(fp_line
			(start 0.12065 -0.305054)
			(end 0.12065 -0.2794)
			(stroke
				(width 0.1)
				(type default)
			)
			(layer "B.Fab")
		)
		(fp_line
			(start 0.67945 -0.305054)
			(end 0.12065 -0.305054)
			(stroke
				(width 0.1)
				(type default)
			)
			(layer "B.Fab")
		)
		(pad "1" smd circle
			(at 0.40005 0 90)
			(size 0 0)
			(layers "B.Cu" "B.Mask" "B.Paste")
			(net "SMB_OCP_V3_2_3V3AUX_SCL")
		)
		(pad "2" smd circle
			(at -0.40005 0 90)
			(size 0 0)
			(layers "B.Cu" "B.Mask" "B.Paste")
			(net "SMB_OCP_V3_2_3V3AUX_SCL_R0")
		)
	)
	(footprint ""
		(layer "B.Cu")
		(at 120.856248 -165.079934 -90)
		(property "Reference" "PC332_2"
			(at 0 0 90)
			(layer "B.SilkS")
			(hide yes)
			(effects
				(font
					(size 1.27 1.27)
				)
				(justify mirror)
			)
		)
		(property "Value" ""
			(at 0 0 90)
			(layer "B.Fab")
			(effects
				(font
					(size 1.27 1.27)
				)
				(justify mirror)
			)
		)
		(duplicate_pad_numbers_are_jumpers no)
		(fp_line
			(start -1.524 0.762)
			(end 1.524 0.762)
			(stroke
				(width 0.1524)
				(type default)
			)
			(layer "B.SilkS")
		)
		(fp_line
			(start 1.524 0.762)
			(end 1.524 -0.762)
			(stroke
				(width 0.1524)
				(type default)
			)
			(layer "B.SilkS")
		)
		(fp_line
			(start -1.524 -0.762)
			(end -1.524 0.762)
			(stroke
				(width 0.1524)
				(type default)
			)
			(layer "B.SilkS")
		)
		(fp_line
			(start 1.524 -0.762)
			(end -1.524 -0.762)
			(stroke
				(width 0.1524)
				(type default)
			)
			(layer "B.SilkS")
		)
		(fp_line
			(start -1.1049 0.724916)
			(end -1.1049 -0.724916)
			(stroke
				(width 0.1)
				(type default)
			)
			(layer "B.Fab")
		)
		(fp_line
			(start 1.1049 0.724916)
			(end -1.1049 0.724916)
			(stroke
				(width 0.1)
				(type default)
			)
			(layer "B.Fab")
		)
		(fp_line
			(start -1.1049 -0.724916)
			(end 1.1049 -0.724916)
			(stroke
				(width 0.1)
				(type default)
			)
			(layer "B.Fab")
		)
		(fp_line
			(start 1.1049 -0.724916)
			(end 1.1049 0.724916)
			(stroke
				(width 0.1)
				(type default)
			)
			(layer "B.Fab")
		)
		(pad "1" smd rect
			(at 0.889 0 270)
			(size 1.016 1.27)
			(layers "B.Cu" "B.Mask" "B.Paste")
			(net "SW_P12V_AUX_PVDDCR_SOC_P1_FLT")
		)
		(pad "2" smd rect
			(at -0.889 0 270)
			(size 1.016 1.27)
			(layers "B.Cu" "B.Mask" "B.Paste")
			(net "GND")
		)
	)
)
